# BASEBOARD_FAB2 (Tioga Pass) — schematic netlist excerpt (pin names and nets, part order shuffled) for the footprints in the layout excerpt that follows; sources: Cadence DE-HDL packaged netlist, KiCad conversion of Wiwynn_Tioga_Pass_MB.brd

R1B4  RES  33.2 1% CHIP  pkg 0402  page 226 : A = IRQ_PVDDQ_KLM_VRHOT_LVT3_R_N ; B = IRQ_PVDDQ_KLM_VRHOT_LVT3_N
R3F3  RES  0.0 5% EMPTY  pkg 0402  page 104 : A = CLK_322M_156M_CPU1_OSC_VRM_DP ; B = CLK_156M_OSC_CPU1_HFI_DP
C7B19  CAP_A  22.0UF 4V 20% X6S  pkg 0603V  page 131 : A = P1V05_PCH_STBY ; B = GND

(kicad_pcb
	(version 20260206)
	(generator "pcbnew")
	(generator_version "10.0")
	(general
		(thickness 1.6)
		(legacy_teardrops no)
	)
	(paper "A4")
	(title_block
		(title "Wiwynn_Tioga_Pass_MB.brd")
		(comment 1 "Tioga Pass / footprints 1055-1057 of 4770")
	)
	(layers
		(0 "F.Cu" signal "TOP")
		(4 "In1.Cu" signal "L2GND")
		(6 "In2.Cu" signal "L3")
		(8 "In3.Cu" signal "L4GND")
		(10 "In4.Cu" signal "L5")
		(12 "In5.Cu" signal "L6GND")
		(14 "In6.Cu" signal "L7VCC")
		(16 "In7.Cu" signal "L8VCC")
		(18 "In8.Cu" signal "L9GND")
		(20 "In9.Cu" signal "L10")
		(22 "In10.Cu" signal "L11GND")
		(24 "In11.Cu" signal "L12")
		(26 "In12.Cu" signal "L13GND")
		(2 "B.Cu" signal "BOTTOM")
		(9 "F.Adhes" user "F.Adhesive")
		(11 "B.Adhes" user "B.Adhesive")
		(13 "F.Paste" user "Package Geometry/Pastemask Top")
		(15 "B.Paste" user "Package Geometry/Pastemask Bottom")
		(5 "F.SilkS" user "Ref Des/Silkscreen Top")
		(7 "B.SilkS" user "Ref Des/Silkscreen Bottom")
		(1 "F.Mask" user "Board Geometry/Soldermask Top")
		(3 "B.Mask" user "Board Geometry/Soldermask Bottom")
		(17 "Dwgs.User" user "User.Drawings")
		(19 "Cmts.User" user "User.Comments")
		(21 "Eco1.User" user "User.Eco1")
		(23 "Eco2.User" user "User.Eco2")
		(25 "Edge.Cuts" user "Board Geometry/Outline")
		(27 "Margin" user)
		(31 "F.CrtYd" user "Package Geometry/Place Bound Top")
		(29 "B.CrtYd" user "Package Geometry/Place Bound Bottom")
		(35 "F.Fab" user "Ref Des/Assembly Top")
		(33 "B.Fab" user "Ref Des/Assembly Bottom")
	)
	(footprint ""
		(layer "F.Cu")
		(at 155.194 -27.9908 180)
		(property "Reference" "R3F3"
			(at 0 0 180)
			(layer "F.SilkS")
			(hide yes)
			(effects
				(font
					(size 1.27 1.27)
				)
			)
		)
		(property "Value" ""
			(at 0 0 180)
			(layer "F.Fab")
			(effects
				(font
					(size 1.27 1.27)
				)
			)
		)
		(duplicate_pad_numbers_are_jumpers no)
		(fp_poly
			(pts
				(xy -0.2794 -0.1016) (xy 0.2794 -0.1016) (xy 0.2794 0.9906) (xy -0.2794 0.9906)
			)
			(stroke
				(width 0)
				(type default)
			)
			(fill no)
			(layer "F.CrtYd")
		)
		(fp_line
			(start 0.2794 0.9906)
			(end 0.2794 -0.1016)
			(stroke
				(width 0.1)
				(type default)
			)
			(layer "F.Fab")
		)
		(fp_line
			(start 0.2794 -0.1016)
			(end -0.2794 -0.1016)
			(stroke
				(width 0.1)
				(type default)
			)
			(layer "F.Fab")
		)
		(fp_line
			(start -0.2794 0.9906)
			(end 0.2794 0.9906)
			(stroke
				(width 0.1)
				(type default)
			)
			(layer "F.Fab")
		)
		(fp_line
			(start -0.2794 -0.1016)
			(end -0.2794 0.9906)
			(stroke
				(width 0.1)
				(type default)
			)
			(layer "F.Fab")
		)
		(pad "1" smd rect
			(at 0 0 180)
			(size 0.508 0.508)
			(layers "F.Cu" "F.Mask" "F.Paste")
			(net "CLK_322M_156M_CPU1_OSC_VRM_DP")
		)
		(pad "2" smd rect
			(at 0 0.889 180)
			(size 0.508 0.508)
			(layers "F.Cu" "F.Mask" "F.Paste")
			(net "CLK_156M_OSC_CPU1_HFI_DP")
		)
		(zone
			(layer "F.Cu")
			(hatch none 0.5)
			(connect_pads
				(clearance 0)
			)
			(min_thickness 0.25)
			(keepout
				(tracks not_allowed)
				(vias allowed)
				(pads allowed)
				(copperpour not_allowed)
				(footprints allowed)
			)
			(placement
				(enabled no)
				(sheetname "")
			)
			(fill
				(thermal_gap 0.5)
				(thermal_bridge_width 0.5)
				(island_removal_mode 0)
			)
			(polygon
				(pts
					(xy 155.448 -28.6258) (xy 154.94 -28.6258) (xy 154.94 -28.2448) (xy 155.448 -28.2448)
				)
			)
		)
		(zone
			(layer "F.Cu")
			(hatch none 0.5)
			(connect_pads
				(clearance 0)
			)
			(min_thickness 0.25)
			(keepout
				(tracks allowed)
				(vias not_allowed)
				(pads allowed)
				(copperpour not_allowed)
				(footprints allowed)
			)
			(placement
				(enabled no)
				(sheetname "")
			)
			(fill
				(thermal_gap 0.5)
				(thermal_bridge_width 0.5)
				(island_removal_mode 0)
			)
			(polygon
				(pts
					(xy 155.448 -28.2448) (xy 154.94 -28.2448) (xy 154.94 -28.6258) (xy 155.448 -28.6258)
				)
			)
		)
	)
	(footprint ""
		(layer "F.Cu")
		(at 394.5763 -147.0152 90)
		(property "Reference" "C7B19"
			(at 0 0 90)
			(layer "F.SilkS")
			(hide yes)
			(effects
				(font
					(size 1.27 1.27)
				)
			)
		)
		(property "Value" ""
			(at 0 0 90)
			(layer "F.Fab")
			(effects
				(font
					(size 1.27 1.27)
				)
			)
		)
		(duplicate_pad_numbers_are_jumpers no)
		(fp_rect
			(start -0.4953 -0.2032)
			(end 0.4953 1.6002)
			(stroke
				(width 0)
				(type default)
			)
			(fill no)
			(layer "F.CrtYd")
		)
		(fp_line
			(start 0.4953 -0.2032)
			(end 0.4953 1.6002)
			(stroke
				(width 0.1)
				(type default)
			)
			(layer "F.Fab")
		)
		(fp_line
			(start -0.4953 -0.2032)
			(end 0.4953 -0.2032)
			(stroke
				(width 0.1)
				(type default)
			)
			(layer "F.Fab")
		)
		(fp_line
			(start 0.4953 1.6002)
			(end -0.4953 1.6002)
			(stroke
				(width 0.1)
				(type default)
			)
			(layer "F.Fab")
		)
		(fp_line
			(start -0.4953 1.6002)
			(end -0.4953 -0.2032)
			(stroke
				(width 0.1)
				(type default)
			)
			(layer "F.Fab")
		)
		(pad "1" smd rect
			(at 0 0 90)
			(size 0.762 0.889)
			(layers "F.Cu" "F.Mask" "F.Paste")
			(net "P1V05_PCH_STBY")
		)
		(pad "2" smd rect
			(at 0 1.397 90)
			(size 0.762 0.889)
			(layers "F.Cu" "F.Mask" "F.Paste")
			(net "GND")
		)
		(zone
			(layer "F.Cu")
			(hatch none 0.5)
			(connect_pads
				(clearance 0)
			)
			(min_thickness 0.25)
			(keepout
				(tracks not_allowed)
				(vias allowed)
				(pads allowed)
				(copperpour not_allowed)
				(footprints allowed)
			)
			(placement
				(enabled no)
				(sheetname "")
			)
			(fill
				(thermal_gap 0.5)
				(thermal_bridge_width 0.5)
				(island_removal_mode 0)
			)
			(polygon
				(pts
					(xy 395.0208 -146.6342) (xy 395.5288 -146.6342) (xy 395.5288 -147.3962) (xy 395.0208 -147.3962)
				)
			)
		)
	)
	(footprint ""
		(layer "F.Cu")
		(at -2.28346 -131.96316 180)
		(property "Reference" "R1B4"
			(at 0 0 180)
			(layer "F.SilkS")
			(hide yes)
			(effects
				(font
					(size 1.27 1.27)
				)
			)
		)
		(property "Value" ""
			(at 0 0 180)
			(layer "F.Fab")
			(effects
				(font
					(size 1.27 1.27)
				)
			)
		)
		(duplicate_pad_numbers_are_jumpers no)
		(fp_poly
			(pts
				(xy -0.2794 -0.1016) (xy 0.2794 -0.1016) (xy 0.2794 0.9906) (xy -0.2794 0.9906)
			)
			(stroke
				(width 0)
				(type default)
			)
			(fill no)
			(layer "F.CrtYd")
		)
		(fp_line
			(start 0.2794 0.9906)
			(end 0.2794 -0.1016)
			(stroke
				(width 0.1)
				(type default)
			)
			(layer "F.Fab")
		)
		(fp_line
			(start 0.2794 -0.1016)
			(end -0.2794 -0.1016)
			(stroke
				(width 0.1)
				(type default)
			)
			(layer "F.Fab")
		)
		(fp_line
			(start -0.2794 0.9906)
			(end 0.2794 0.9906)
			(stroke
				(width 0.1)
				(type default)
			)
			(layer "F.Fab")
		)
		(fp_line
			(start -0.2794 -0.1016)
			(end -0.2794 0.9906)
			(stroke
				(width 0.1)
				(type default)
			)
			(layer "F.Fab")
		)
		(pad "1" smd rect
			(at 0 0 180)
			(size 0.508 0.508)
			(layers "F.Cu" "F.Mask" "F.Paste")
			(net "IRQ_PVDDQ_KLM_VRHOT_LVT3_R_N")
		)
		(pad "2" smd rect
			(at 0 0.889 180)
			(size 0.508 0.508)
			(layers "F.Cu" "F.Mask" "F.Paste")
			(net "IRQ_PVDDQ_KLM_VRHOT_LVT3_N")
		)
		(zone
			(layer "F.Cu")
			(hatch none 0.5)
			(connect_pads
				(clearance 0)
			)
			(min_thickness 0.25)
			(keepout
				(tracks not_allowed)
				(vias allowed)
				(pads allowed)
				(copperpour not_allowed)
				(footprints allowed)
			)
			(placement
				(enabled no)
				(sheetname "")
			)
			(fill
				(thermal_gap 0.5)
				(thermal_bridge_width 0.5)
				(island_removal_mode 0)
			)
			(polygon
				(pts
					(xy -2.02946 -132.59816) (xy -2.53746 -132.59816) (xy -2.53746 -132.21716) (xy -2.02946 -132.21716)
				)
			)
		)
		(zone
			(layer "F.Cu")
			(hatch none 0.5)
			(connect_pads
				(clearance 0)
			)
			(min_thickness 0.25)
			(keepout
				(tracks allowed)
				(vias not_allowed)
				(pads allowed)
				(copperpour not_allowed)
				(footprints allowed)
			)
			(placement
				(enabled no)
				(sheetname "")
			)
			(fill
				(thermal_gap 0.5)
				(thermal_bridge_width 0.5)
				(island_removal_mode 0)
			)
			(polygon
				(pts
					(xy -2.02946 -132.21716) (xy -2.53746 -132.21716) (xy -2.53746 -132.59816) (xy -2.02946 -132.59816)
				)
			)
		)
	)
)
